(kicad_pcb
	(version 20260206)
	(generator "pcbnew")
	(generator_version "10.0")
	(general
		(thickness 1.6)
		(legacy_teardrops no)
	)
	(paper "A4")
	(title_block
		(title "03242023_DA0F0TMBIJ0_F0T_Motherboard_J_brd_V01_OCP.brd")
		(comment 1 "Grand Teton / footprint 1682 of 6105 (U1), pads 3568-3678 of 4677")
	)
	(layers
		(0 "F.Cu" signal "TOP")
		(4 "In1.Cu" signal "GND")
		(6 "In2.Cu" signal "IN1")
		(8 "In3.Cu" signal "GND1")
		(10 "In4.Cu" signal "IN2")
		(12 "In5.Cu" signal "GND2")
		(14 "In6.Cu" signal "IN3")
		(16 "In7.Cu" signal "GND3")
		(18 "In8.Cu" signal "VCC")
		(20 "In9.Cu" signal "VCC1")
		(22 "In10.Cu" signal "GND4")
		(24 "In11.Cu" signal "IN4")
		(26 "In12.Cu" signal "GND5")
		(28 "In13.Cu" signal "IN5")
		(30 "In14.Cu" signal "GND6")
		(32 "In15.Cu" signal "IN6")
		(34 "In16.Cu" signal "GND7")
		(2 "B.Cu" signal "BOTTOM")
		(9 "F.Adhes" user "F.Adhesive")
		(11 "B.Adhes" user "B.Adhesive")
		(13 "F.Paste" user "Package Geometry/Pastemask Top")
		(15 "B.Paste" user "Package Geometry/Pastemask Bottom")
		(5 "F.SilkS" user "Ref Des/Silkscreen Top")
		(7 "B.SilkS" user "Ref Des/Silkscreen Bottom")
		(1 "F.Mask" user "Board Geometry/Soldermask Top")
		(3 "B.Mask" user "Board Geometry/Soldermask Bottom")
		(17 "Dwgs.User" user "User.Drawings")
		(19 "Cmts.User" user "User.Comments")
		(21 "Eco1.User" user "User.Eco1")
		(23 "Eco2.User" user "User.Eco2")
		(25 "Edge.Cuts" user "Board Geometry/Outline")
		(27 "Margin" user)
		(31 "F.CrtYd" user "Package Geometry/Place Bound Top")
		(29 "B.CrtYd" user "Package Geometry/Place Bound Bottom")
		(35 "F.Fab" user "Ref Des/Assembly Top")
		(33 "B.Fab" user "Ref Des/Assembly Bottom")
	)
	(footprint ""
		(layer "F.Cu")
		(at 111.93018 -251.76988 90)
		(property "Reference" "U1"
			(at -74.913236 41.548812 0)
			(unlocked yes)
			(layer "F.SilkS")
			(effects
				(font
					(size 1.6002 1.1938)
					(thickness 0.1524)
				)
				(justify left)
			)
		)
		(property "Value" ""
			(at 0 0 90)
			(layer "F.Fab")
			(effects
				(font
					(size 1.27 1.27)
				)
			)
		)
		(duplicate_pad_numbers_are_jumpers no)
		(pad "EF24" smd circle
			(at -18.705576 22.265386 270)
			(size 0.4318 0.4318)
			(layers "F.Cu" "F.Mask" "F.Paste")
			(net "GND")
		)
		(pad "EF26" smd circle
			(at -17.07769 22.265386 270)
			(size 0.4318 0.4318)
			(layers "F.Cu" "F.Mask" "F.Paste")
			(net "GND")
		)
		(pad "EF28" smd circle
			(at -15.450058 22.265386 270)
			(size 0.4318 0.4318)
			(layers "F.Cu" "F.Mask" "F.Paste")
			(net "GND")
		)
		(pad "EF30" smd circle
			(at -13.822426 22.265386 270)
			(size 0.4318 0.4318)
			(layers "F.Cu" "F.Mask" "F.Paste")
			(net "GND")
		)
		(pad "EF32" smd circle
			(at -12.19454 22.265386 270)
			(size 0.4318 0.4318)
			(layers "F.Cu" "F.Mask" "F.Paste")
			(net "GND")
		)
		(pad "EF34" smd circle
			(at -10.566654 22.265386 270)
			(size 0.4318 0.4318)
			(layers "F.Cu" "F.Mask" "F.Paste")
			(net "GND")
		)
		(pad "EF36" smd circle
			(at -8.939022 22.265386 270)
			(size 0.4318 0.4318)
			(layers "F.Cu" "F.Mask" "F.Paste")
			(net "GND")
		)
		(pad "EF38" smd circle
			(at -7.311136 22.265386 270)
			(size 0.4318 0.4318)
			(layers "F.Cu" "F.Mask" "F.Paste")
			(net "GND")
		)
		(pad "EF40" smd circle
			(at -5.68325 22.265386 270)
			(size 0.4318 0.4318)
			(layers "F.Cu" "F.Mask" "F.Paste")
			(net "GND")
		)
		(pad "EF42" smd circle
			(at -4.055618 22.265386 270)
			(size 0.4318 0.4318)
			(layers "F.Cu" "F.Mask" "F.Paste")
			(net "GND")
		)
		(pad "EF44" smd circle
			(at -2.427732 22.265386 270)
			(size 0.4318 0.4318)
			(layers "F.Cu" "F.Mask" "F.Paste")
			(net "GND")
		)
		(pad "EF47" smd circle
			(at 1.613916 22.375114 270)
			(size 0.4318 0.4318)
			(layers "F.Cu" "F.Mask" "F.Paste")
			(net "GND")
		)
		(pad "EF49" smd circle
			(at 3.241802 22.375114 270)
			(size 0.4318 0.4318)
			(layers "F.Cu" "F.Mask" "F.Paste")
			(net "GND")
		)
		(pad "EF51" smd circle
			(at 4.869434 22.375114 270)
			(size 0.4318 0.4318)
			(layers "F.Cu" "F.Mask" "F.Paste")
			(net "GND")
		)
		(pad "EF53" smd circle
			(at 6.49732 22.375114 270)
			(size 0.4318 0.4318)
			(layers "F.Cu" "F.Mask" "F.Paste")
			(net "GND")
		)
		(pad "EF55" smd circle
			(at 8.124952 22.375114 270)
			(size 0.4318 0.4318)
			(layers "F.Cu" "F.Mask" "F.Paste")
			(net "GND")
		)
		(pad "EF57" smd circle
			(at 9.752838 22.375114 270)
			(size 0.4318 0.4318)
			(layers "F.Cu" "F.Mask" "F.Paste")
			(net "GND")
		)
		(pad "EF59" smd circle
			(at 11.380724 22.375114 270)
			(size 0.4318 0.4318)
			(layers "F.Cu" "F.Mask" "F.Paste")
			(net "GND")
		)
		(pad "EF61" smd circle
			(at 13.008356 22.375114 270)
			(size 0.4318 0.4318)
			(layers "F.Cu" "F.Mask" "F.Paste")
			(net "GND")
		)
		(pad "EF63" smd circle
			(at 14.635988 22.375114 270)
			(size 0.4318 0.4318)
			(layers "F.Cu" "F.Mask" "F.Paste")
			(net "GND")
		)
		(pad "EF65" smd circle
			(at 16.263874 22.375114 270)
			(size 0.4318 0.4318)
			(layers "F.Cu" "F.Mask" "F.Paste")
			(net "GND")
		)
		(pad "EF67" smd circle
			(at 17.89176 22.375114 270)
			(size 0.4318 0.4318)
			(layers "F.Cu" "F.Mask" "F.Paste")
			(net "GND")
		)
		(pad "EF69" smd circle
			(at 19.519392 22.375114 270)
			(size 0.4318 0.4318)
			(layers "F.Cu" "F.Mask" "F.Paste")
			(net "GND")
		)
		(pad "EF71" smd circle
			(at 21.147278 22.375114 270)
			(size 0.4318 0.4318)
			(layers "F.Cu" "F.Mask" "F.Paste")
			(net "GND")
		)
		(pad "EF73" smd circle
			(at 22.77491 22.375114 270)
			(size 0.4318 0.4318)
			(layers "F.Cu" "F.Mask" "F.Paste")
			(net "GND")
		)
		(pad "EF75" smd circle
			(at 24.402796 22.375114 270)
			(size 0.4318 0.4318)
			(layers "F.Cu" "F.Mask" "F.Paste")
			(net "GND")
		)
		(pad "EF77" smd circle
			(at 26.030682 22.375114 270)
			(size 0.4318 0.4318)
			(layers "F.Cu" "F.Mask" "F.Paste")
			(net "GND")
		)
		(pad "EF79" smd circle
			(at 27.658314 22.375114 270)
			(size 0.4318 0.4318)
			(layers "F.Cu" "F.Mask" "F.Paste")
			(net "PVCCFA_EHV_FIVRA_CPU1")
		)
		(pad "EF81" smd circle
			(at 29.2862 22.375114 270)
			(size 0.4318 0.4318)
			(layers "F.Cu" "F.Mask" "F.Paste")
			(net "GND")
		)
		(pad "EF83" smd circle
			(at 30.914086 22.375114 270)
			(size 0.4318 0.4318)
			(layers "F.Cu" "F.Mask" "F.Paste")
			(net "GND")
		)
		(pad "EF85" smd circle
			(at 32.541718 22.375114 270)
			(size 0.4318 0.4318)
			(layers "F.Cu" "F.Mask" "F.Paste")
			(net "GND")
		)
		(pad "EF87" smd circle
			(at 34.169604 22.375114 270)
			(size 0.4318 0.4318)
			(layers "F.Cu" "F.Mask" "F.Paste")
			(net "GND")
		)
		(pad "EF89" smd circle
			(at 35.797236 22.375114 270)
			(size 0.4318 0.4318)
			(layers "F.Cu" "F.Mask" "F.Paste")
			(net "GND")
		)
		(pad "EG3" smd circle
			(at -35.797236 22.735286 270)
			(size 0.4318 0.4318)
			(layers "F.Cu" "F.Mask" "F.Paste")
			(net "UPI_CPU0_CPU1_P0P1_DP<1>")
		)
		(pad "EG5" smd circle
			(at -34.169604 22.735286 270)
			(size 0.4318 0.4318)
			(layers "F.Cu" "F.Mask" "F.Paste")
			(net "GND")
		)
		(pad "EG7" smd circle
			(at -32.541718 22.735286 270)
			(size 0.4318 0.4318)
			(layers "F.Cu" "F.Mask" "F.Paste")
			(net "GND")
		)
		(pad "EG9" smd circle
			(at -30.914086 22.735286 270)
			(size 0.4318 0.4318)
			(layers "F.Cu" "F.Mask" "F.Paste")
			(net "GND")
		)
		(pad "EG11" smd circle
			(at -29.2862 22.735286 270)
			(size 0.4318 0.4318)
			(layers "F.Cu" "F.Mask" "F.Paste")
			(net "P5E_CPU1_PE2_RX_DP<15>")
		)
		(pad "EG13" smd circle
			(at -27.658314 22.735286 270)
			(size 0.4318 0.4318)
			(layers "F.Cu" "F.Mask" "F.Paste")
			(net "GND")
		)
		(pad "EG15" smd circle
			(at -26.030682 22.735286 270)
			(size 0.4318 0.4318)
			(layers "F.Cu" "F.Mask" "F.Paste")
			(net "P5E_CPU1_PE2_TX_DP<15>")
		)
		(pad "EG17" smd circle
			(at -24.402796 22.735286 270)
			(size 0.4318 0.4318)
			(layers "F.Cu" "F.Mask" "F.Paste")
			(net "NC_CPU1_HBM0_VIEWDIG1")
		)
		(pad "EG19" smd circle
			(at -22.77491 22.735286 270)
			(size 0.4318 0.4318)
			(layers "F.Cu" "F.Mask" "F.Paste")
			(net "M_F_CPU1_SB_DQ<15>")
		)
		(pad "EG21" smd circle
			(at -21.147278 22.735286 270)
			(size 0.4318 0.4318)
			(layers "F.Cu" "F.Mask" "F.Paste")
			(net "M_F_CPU1_SB_DQS_DP<6>")
		)
		(pad "EG23" smd circle
			(at -19.519392 22.735286 270)
			(size 0.4318 0.4318)
			(layers "F.Cu" "F.Mask" "F.Paste")
			(net "M_F_CPU1_SB_DQ<10>")
		)
		(pad "EG25" smd circle
			(at -17.89176 22.735286 270)
			(size 0.4318 0.4318)
			(layers "F.Cu" "F.Mask" "F.Paste")
			(net "M_E_CPU1_SB_DQ<7>")
		)
		(pad "EG27" smd circle
			(at -16.263874 22.735286 270)
			(size 0.4318 0.4318)
			(layers "F.Cu" "F.Mask" "F.Paste")
			(net "M_E_CPU1_SB_DQS_DP<5>")
		)
		(pad "EG29" smd circle
			(at -14.635988 22.735286 270)
			(size 0.4318 0.4318)
			(layers "F.Cu" "F.Mask" "F.Paste")
			(net "M_E_CPU1_SB_DQ<2>")
		)
		(pad "EG31" smd circle
			(at -13.008356 22.735286 270)
			(size 0.4318 0.4318)
			(layers "F.Cu" "F.Mask" "F.Paste")
			(net "M_F_CPU1_SB_CB<3>")
		)
		(pad "EG33" smd circle
			(at -11.380724 22.735286 270)
			(size 0.4318 0.4318)
			(layers "F.Cu" "F.Mask" "F.Paste")
			(net "M_F_CPU1_SB_DQS_DP<4>")
		)
		(pad "EG35" smd circle
			(at -9.752838 22.735286 270)
			(size 0.4318 0.4318)
			(layers "F.Cu" "F.Mask" "F.Paste")
			(net "M_F_CPU1_SB_CB<6>")
		)
		(pad "EG37" smd circle
			(at -8.124952 22.735286 270)
			(size 0.4318 0.4318)
			(layers "F.Cu" "F.Mask" "F.Paste")
			(net "M_F_CPU1_SB_CS_N<1>")
		)
		(pad "EG39" smd circle
			(at -6.49732 22.735286 270)
			(size 0.4318 0.4318)
			(layers "F.Cu" "F.Mask" "F.Paste")
			(net "GND")
		)
		(pad "EG41" smd circle
			(at -4.869434 22.735286 270)
			(size 0.4318 0.4318)
			(layers "F.Cu" "F.Mask" "F.Paste")
			(net "M_F_CPU1_SB_CA<3>")
		)
		(pad "EG43" smd circle
			(at -3.241802 22.735286 270)
			(size 0.4318 0.4318)
			(layers "F.Cu" "F.Mask" "F.Paste")
			(net "M_E_CPU1_SB_CA<0>")
		)
		(pad "EG45" smd circle
			(at -1.613916 22.735286 270)
			(size 0.4318 0.4318)
			(layers "F.Cu" "F.Mask" "F.Paste")
			(net "M_E_CPU1_CLK_DP<0>")
		)
		(pad "EG48" smd circle
			(at 2.427732 22.845268 270)
			(size 0.4318 0.4318)
			(layers "F.Cu" "F.Mask" "F.Paste")
			(net "M_H_CPU1_SA_RSP<0>")
		)
		(pad "EG50" smd circle
			(at 4.055618 22.845268 270)
			(size 0.4318 0.4318)
			(layers "F.Cu" "F.Mask" "F.Paste")
			(net "M_F_CPU1_SA_CA<5>")
		)
		(pad "EG52" smd circle
			(at 5.68325 22.845268 270)
			(size 0.4318 0.4318)
			(layers "F.Cu" "F.Mask" "F.Paste")
			(net "GND")
		)
		(pad "EG54" smd circle
			(at 7.311136 22.845268 270)
			(size 0.4318 0.4318)
			(layers "F.Cu" "F.Mask" "F.Paste")
			(net "M_F_CPU1_SA_CS_N<0>")
		)
		(pad "EG56" smd circle
			(at 8.939022 22.845268 270)
			(size 0.4318 0.4318)
			(layers "F.Cu" "F.Mask" "F.Paste")
			(net "M_F_CPU1_SA_CB<7>")
		)
		(pad "EG58" smd circle
			(at 10.566654 22.845268 270)
			(size 0.4318 0.4318)
			(layers "F.Cu" "F.Mask" "F.Paste")
			(net "M_F_CPU1_SA_DQS_DP<9>")
		)
		(pad "EG60" smd circle
			(at 12.19454 22.845268 270)
			(size 0.4318 0.4318)
			(layers "F.Cu" "F.Mask" "F.Paste")
			(net "M_F_CPU1_SA_CB<2>")
		)
		(pad "EG62" smd circle
			(at 13.822426 22.845268 270)
			(size 0.4318 0.4318)
			(layers "F.Cu" "F.Mask" "F.Paste")
			(net "M_F_CPU1_SA_DQ<23>")
		)
		(pad "EG64" smd circle
			(at 15.450058 22.845268 270)
			(size 0.4318 0.4318)
			(layers "F.Cu" "F.Mask" "F.Paste")
			(net "M_F_CPU1_SA_DQS_DP<7>")
		)
		(pad "EG66" smd circle
			(at 17.07769 22.845268 270)
			(size 0.4318 0.4318)
			(layers "F.Cu" "F.Mask" "F.Paste")
			(net "M_F_CPU1_SA_DQ<18>")
		)
		(pad "EG68" smd circle
			(at 18.705576 22.845268 270)
			(size 0.4318 0.4318)
			(layers "F.Cu" "F.Mask" "F.Paste")
			(net "M_E_CPU1_SA_DQ<15>")
		)
		(pad "EG70" smd circle
			(at 20.333462 22.845268 270)
			(size 0.4318 0.4318)
			(layers "F.Cu" "F.Mask" "F.Paste")
			(net "M_E_CPU1_SA_DQS_DP<6>")
		)
		(pad "EG72" smd circle
			(at 21.961094 22.845268 270)
			(size 0.4318 0.4318)
			(layers "F.Cu" "F.Mask" "F.Paste")
			(net "M_E_CPU1_SA_DQ<10>")
		)
		(pad "EG74" smd circle
			(at 23.58898 22.845268 270)
			(size 0.4318 0.4318)
			(layers "F.Cu" "F.Mask" "F.Paste")
			(net "M_F_CPU1_SA_DQ<7>")
		)
		(pad "EG76" smd circle
			(at 25.216612 22.845268 270)
			(size 0.4318 0.4318)
			(layers "F.Cu" "F.Mask" "F.Paste")
			(net "M_F_CPU1_SA_DQS_DP<5>")
		)
		(pad "EG78" smd circle
			(at 26.844498 22.845268 270)
			(size 0.4318 0.4318)
			(layers "F.Cu" "F.Mask" "F.Paste")
			(net "M_F_CPU1_SA_DQ<3>")
		)
		(pad "EG80" smd circle
			(at 28.472384 22.845268 270)
			(size 0.4318 0.4318)
			(layers "F.Cu" "F.Mask" "F.Paste")
			(net "PVCCFA_EHV_FIVRA_CPU1")
		)
		(pad "EG82" smd circle
			(at 30.100016 22.845268 270)
			(size 0.4318 0.4318)
			(layers "F.Cu" "F.Mask" "F.Paste")
			(net "GND")
		)
		(pad "EG84" smd circle
			(at 31.727902 22.845268 270)
			(size 0.4318 0.4318)
			(layers "F.Cu" "F.Mask" "F.Paste")
			(net "GND")
		)
		(pad "EG86" smd circle
			(at 33.355534 22.845268 270)
			(size 0.4318 0.4318)
			(layers "F.Cu" "F.Mask" "F.Paste")
			(net "GND")
		)
		(pad "EG88" smd circle
			(at 34.98342 22.845268 270)
			(size 0.4318 0.4318)
			(layers "F.Cu" "F.Mask" "F.Paste")
			(net "GND")
		)
		(pad "EG90" smd oval
			(at 36.611306 22.845268 315)
			(size 0.381 0.4826)
			(drill
				(offset 0 -0.0508)
			)
			(layers "F.Cu" "F.Mask" "F.Paste")
			(net "GND")
		)
		(pad "EH2" smd oval
			(at -36.611306 23.204932 225)
			(size 0.381 0.4826)
			(drill
				(offset 0 -0.0508)
			)
			(layers "F.Cu" "F.Mask" "F.Paste")
			(net "UPI_CPU0_CPU1_P0P1_DN<0>")
		)
		(pad "EH4" smd circle
			(at -34.98342 23.204932 270)
			(size 0.4318 0.4318)
			(layers "F.Cu" "F.Mask" "F.Paste")
			(net "GND")
		)
		(pad "EH6" smd circle
			(at -33.355534 23.204932 270)
			(size 0.4318 0.4318)
			(layers "F.Cu" "F.Mask" "F.Paste")
			(net "GND")
		)
		(pad "EH8" smd circle
			(at -31.727902 23.204932 270)
			(size 0.4318 0.4318)
			(layers "F.Cu" "F.Mask" "F.Paste")
			(net "M_G_CPU1_SB_DQ<25>")
		)
		(pad "EH10" smd circle
			(at -30.100016 23.204932 270)
			(size 0.4318 0.4318)
			(layers "F.Cu" "F.Mask" "F.Paste")
			(net "P5E_CPU1_PE2_RX_DN<15>")
		)
		(pad "EH12" smd circle
			(at -28.472384 23.204932 270)
			(size 0.4318 0.4318)
			(layers "F.Cu" "F.Mask" "F.Paste")
			(net "GND")
		)
		(pad "EH14" smd circle
			(at -26.844498 23.204932 270)
			(size 0.4318 0.4318)
			(layers "F.Cu" "F.Mask" "F.Paste")
			(net "GND")
		)
		(pad "EH16" smd circle
			(at -25.216612 23.204932 270)
			(size 0.4318 0.4318)
			(layers "F.Cu" "F.Mask" "F.Paste")
			(net "GND")
		)
		(pad "EH18" smd circle
			(at -23.58898 23.204932 270)
			(size 0.4318 0.4318)
			(layers "F.Cu" "F.Mask" "F.Paste")
			(net "GND")
		)
		(pad "EH20" smd circle
			(at -21.961094 23.204932 270)
			(size 0.4318 0.4318)
			(layers "F.Cu" "F.Mask" "F.Paste")
			(net "M_F_CPU1_SB_DQ<14>")
		)
		(pad "EH22" smd circle
			(at -20.333462 23.204932 270)
			(size 0.4318 0.4318)
			(layers "F.Cu" "F.Mask" "F.Paste")
			(net "M_F_CPU1_SB_DQ<11>")
		)
		(pad "EH24" smd circle
			(at -18.705576 23.204932 270)
			(size 0.4318 0.4318)
			(layers "F.Cu" "F.Mask" "F.Paste")
			(net "GND")
		)
		(pad "EH26" smd circle
			(at -17.07769 23.204932 270)
			(size 0.4318 0.4318)
			(layers "F.Cu" "F.Mask" "F.Paste")
			(net "M_E_CPU1_SB_DQ<6>")
		)
		(pad "EH28" smd circle
			(at -15.450058 23.204932 270)
			(size 0.4318 0.4318)
			(layers "F.Cu" "F.Mask" "F.Paste")
			(net "M_E_CPU1_SB_DQ<3>")
		)
		(pad "EH30" smd circle
			(at -13.822426 23.204932 270)
			(size 0.4318 0.4318)
			(layers "F.Cu" "F.Mask" "F.Paste")
			(net "GND")
		)
		(pad "EH32" smd circle
			(at -12.19454 23.204932 270)
			(size 0.4318 0.4318)
			(layers "F.Cu" "F.Mask" "F.Paste")
			(net "M_F_CPU1_SB_CB<2>")
		)
		(pad "EH34" smd circle
			(at -10.566654 23.204932 270)
			(size 0.4318 0.4318)
			(layers "F.Cu" "F.Mask" "F.Paste")
			(net "M_F_CPU1_SB_CB<7>")
		)
		(pad "EH36" smd circle
			(at -8.939022 23.204932 270)
			(size 0.4318 0.4318)
			(layers "F.Cu" "F.Mask" "F.Paste")
			(net "GND")
		)
		(pad "EH38" smd circle
			(at -7.311136 23.204932 270)
			(size 0.4318 0.4318)
			(layers "F.Cu" "F.Mask" "F.Paste")
			(net "M_F_CPU1_SB_CS_N<0>")
		)
		(pad "EH40" smd circle
			(at -5.68325 23.204932 270)
			(size 0.4318 0.4318)
			(layers "F.Cu" "F.Mask" "F.Paste")
			(net "M_F_CPU1_SB_CA<5>")
		)
		(pad "EH42" smd circle
			(at -4.055618 23.204932 270)
			(size 0.4318 0.4318)
			(layers "F.Cu" "F.Mask" "F.Paste")
			(net "GND")
		)
		(pad "EH44" smd circle
			(at -2.427732 23.204932 270)
			(size 0.4318 0.4318)
			(layers "F.Cu" "F.Mask" "F.Paste")
			(net "M_E_CPU1_SB_CA<1>")
		)
		(pad "EH47" smd circle
			(at 1.613916 23.314914 270)
			(size 0.4318 0.4318)
			(layers "F.Cu" "F.Mask" "F.Paste")
			(net "M_H_CPU1_SA_RSP<1>")
		)
		(pad "EH49" smd circle
			(at 3.241802 23.314914 270)
			(size 0.4318 0.4318)
			(layers "F.Cu" "F.Mask" "F.Paste")
			(net "GND")
		)
		(pad "EH51" smd circle
			(at 4.869434 23.314914 270)
			(size 0.4318 0.4318)
			(layers "F.Cu" "F.Mask" "F.Paste")
			(net "M_F_CPU1_SA_CA<3>")
		)
		(pad "EH53" smd circle
			(at 6.49732 23.314914 270)
			(size 0.4318 0.4318)
			(layers "F.Cu" "F.Mask" "F.Paste")
			(net "M_F_CPU1_SA_CS_N<1>")
		)
		(pad "EH55" smd circle
			(at 8.124952 23.314914 270)
			(size 0.4318 0.4318)
			(layers "F.Cu" "F.Mask" "F.Paste")
			(net "GND")
		)
		(pad "EH57" smd circle
			(at 9.752838 23.314914 270)
			(size 0.4318 0.4318)
			(layers "F.Cu" "F.Mask" "F.Paste")
			(net "M_F_CPU1_SA_CB<6>")
		)
		(pad "EH59" smd circle
			(at 11.380724 23.314914 270)
			(size 0.4318 0.4318)
			(layers "F.Cu" "F.Mask" "F.Paste")
			(net "M_F_CPU1_SA_CB<3>")
		)
		(pad "EH61" smd circle
			(at 13.008356 23.314914 270)
			(size 0.4318 0.4318)
			(layers "F.Cu" "F.Mask" "F.Paste")
			(net "GND")
		)
		(pad "EH63" smd circle
			(at 14.635988 23.314914 270)
			(size 0.4318 0.4318)
			(layers "F.Cu" "F.Mask" "F.Paste")
			(net "M_F_CPU1_SA_DQ<22>")
		)
		(pad "EH65" smd circle
			(at 16.263874 23.314914 270)
			(size 0.4318 0.4318)
			(layers "F.Cu" "F.Mask" "F.Paste")
			(net "M_F_CPU1_SA_DQ<19>")
		)
		(pad "EH67" smd circle
			(at 17.89176 23.314914 270)
			(size 0.4318 0.4318)
			(layers "F.Cu" "F.Mask" "F.Paste")
			(net "GND")
		)
		(pad "EH69" smd circle
			(at 19.519392 23.314914 270)
			(size 0.4318 0.4318)
			(layers "F.Cu" "F.Mask" "F.Paste")
			(net "M_E_CPU1_SA_DQ<14>")
		)
	)
)
